(kicad_pcb
	(version 20240108)
	(generator "pcbnew")
	(generator_version "8.0")
	(general
		(thickness 1.62)
		(legacy_teardrops no)
	)
	(paper "A4")
	(title_block
		(title "Jetson Orin Baseboard")
		(date "2025-03-12")
		(rev "1.3.4")
		(company "Antmicro Ltd")
		(comment 1 "www.antmicro.com")
		(comment 9 "footprints 615-617 of 677")
	)
	(layers
		(0 "F.Cu" signal)
		(1 "In1.Cu" signal)
		(2 "In2.Cu" signal)
		(3 "In3.Cu" signal)
		(4 "In4.Cu" jumper)
		(5 "In5.Cu" signal)
		(6 "In6.Cu" signal)
		(31 "B.Cu" signal)
		(32 "B.Adhes" user "B.Adhesive")
		(33 "F.Adhes" user "F.Adhesive")
		(34 "B.Paste" user)
		(35 "F.Paste" user)
		(36 "B.SilkS" user "B.Silkscreen")
		(37 "F.SilkS" user "F.Silkscreen")
		(38 "B.Mask" user)
		(39 "F.Mask" user)
		(40 "Dwgs.User" user "User.Drawings")
		(41 "Cmts.User" user "User.Comments")
		(42 "Eco1.User" user "User.Eco1")
		(43 "Eco2.User" user "User.Eco2")
		(44 "Edge.Cuts" user)
		(45 "Margin" user)
		(46 "B.CrtYd" user "B.Courtyard")
		(47 "F.CrtYd" user "F.Courtyard")
		(48 "B.Fab" user)
		(49 "F.Fab" user)
	)
	(footprint "antmicro-footprints:C_0603_1608Metric"
		(layer "B.Cu")
		(at 45.175 124.245 90)
		(descr "Capacitor SMD 0603")
		(tags "capacitor 0603")
		(property "Reference" "C32"
			(at 3.255 -0.175 -90)
			(layer "B.SilkS")
			(effects
				(font
					(size 0.7 0.7)
					(thickness 0.15)
				)
				(justify left bottom mirror)
			)
		)
		(property "Value" "C_10u_25V_0603"
			(at 0 -1.6 -90)
			(layer "B.Fab")
			(effects
				(font
					(size 0.7 0.7)
					(thickness 0.15)
				)
				(justify left bottom mirror)
			)
		)
		(property "Footprint" "antmicro-footprints:C_0603_1608Metric"
			(at 0 0 90)
			(layer "F.Fab")
			(hide yes)
			(effects
				(font
					(size 1.27 1.27)
					(thickness 0.15)
				)
			)
		)
		(property "Datasheet" "https://product.tdk.com/en/search/capacitor/ceramic/mlcc/info?part_no=C1608X5R1E106M080AC"
			(at 0 0 90)
			(layer "F.Fab")
			(hide yes)
			(effects
				(font
					(size 1.27 1.27)
					(thickness 0.15)
				)
			)
		)
		(property "Author" "Antmicro"
			(at 169.42 79.07 0)
			(layer "B.Fab")
			(hide yes)
			(effects
				(font
					(size 1 1)
					(thickness 0.15)
				)
				(justify mirror)
			)
		)
		(property "Dielectric" ""
			(at 169.42 79.07 0)
			(layer "B.Fab")
			(hide yes)
			(effects
				(font
					(size 1 1)
					(thickness 0.15)
				)
				(justify mirror)
			)
		)
		(property "License" "Apache-2.0"
			(at 169.42 79.07 0)
			(layer "B.Fab")
			(hide yes)
			(effects
				(font
					(size 1 1)
					(thickness 0.15)
				)
				(justify mirror)
			)
		)
		(property "MPN" "C1608X5R1E106M080AC"
			(at 169.42 79.07 0)
			(layer "B.Fab")
			(hide yes)
			(effects
				(font
					(size 1 1)
					(thickness 0.15)
				)
				(justify mirror)
			)
		)
		(property "Manufacturer" "TDK"
			(at 169.42 79.07 0)
			(layer "B.Fab")
			(hide yes)
			(effects
				(font
					(size 1 1)
					(thickness 0.15)
				)
				(justify mirror)
			)
		)
		(property "Val" "10u"
			(at 169.42 79.07 0)
			(layer "B.Fab")
			(hide yes)
			(effects
				(font
					(size 1 1)
					(thickness 0.15)
				)
				(justify mirror)
			)
		)
		(property "Voltage" "25V"
			(at 169.42 79.07 0)
			(layer "B.Fab")
			(hide yes)
			(effects
				(font
					(size 1 1)
					(thickness 0.15)
				)
				(justify mirror)
			)
		)
		(sheetname "USB Debug, DP")
		(sheetfile "usb.kicad_sch")
		(attr smd)
		(fp_line
			(start 0.15 -0.4)
			(end -0.15 -0.4)
			(stroke
				(width 0.15)
				(type solid)
			)
			(layer "B.SilkS")
		)
		(fp_line
			(start 0.15 0.4)
			(end -0.15 0.4)
			(stroke
				(width 0.15)
				(type solid)
			)
			(layer "B.SilkS")
		)
		(fp_rect
			(start -1.25 0.65)
			(end 1.25 -0.65)
			(stroke
				(width 0.05)
				(type solid)
			)
			(fill none)
			(layer "B.CrtYd")
		)
		(fp_rect
			(start -0.8 0.4)
			(end 0.8 -0.4)
			(stroke
				(width 0.15)
				(type solid)
			)
			(fill none)
			(layer "B.Fab")
		)
		(fp_text user "License: Apache-2.0"
			(at -1.682 -5.895 -90)
			(layer "B.Fab")
			(hide yes)
			(effects
				(font
					(size 0.7 0.7)
					(thickness 0.15)
				)
				(justify left bottom mirror)
			)
		)
		(fp_text user "Author: Antmicro"
			(at -1.682 -4.894 -90)
			(layer "B.Fab")
			(hide yes)
			(effects
				(font
					(size 0.7 0.7)
					(thickness 0.15)
				)
				(justify left bottom mirror)
			)
		)
		(fp_text user "${REFERENCE}"
			(at -1.682 -3.895 -90)
			(layer "B.Fab")
			(hide yes)
			(effects
				(font
					(size 0.7 0.7)
					(thickness 0.15)
				)
				(justify left bottom mirror)
			)
		)
		(pad "1" smd roundrect
			(at -0.7 0 90)
			(size 0.8 1)
			(layers "B.Cu" "B.Paste" "B.Mask")
			(roundrect_rratio 0.2)
			(net 196 "/USB Debug, DP/USBC3_VBUS")
			(pintype "passive")
		)
		(pad "2" smd roundrect
			(at 0.7 0 90)
			(size 0.8 1)
			(layers "B.Cu" "B.Paste" "B.Mask")
			(roundrect_rratio 0.2)
			(net 1 "GND")
			(pintype "passive")
		)
	)
	(footprint "antmicro-footprints:VQFN-16-1EP_3x3mm_P0.5mm_EP1.68x1.68mm"
		(layer "B.Cu")
		(at 89.5 109.5 -90)
		(property "Reference" "U34"
			(at -1.56 -2.7 90)
			(layer "B.SilkS")
			(effects
				(font
					(size 0.7 0.7)
					(thickness 0.15)
				)
				(justify left bottom mirror)
			)
		)
		(property "Value" "PCAL6408A_VQFN"
			(at 0 -2.999 90)
			(layer "B.Fab")
			(effects
				(font
					(size 0.7 0.7)
					(thickness 0.15)
				)
				(justify left bottom mirror)
			)
		)
		(property "Footprint" "antmicro-footprints:VQFN-16-1EP_3x3mm_P0.5mm_EP1.68x1.68mm"
			(at 0 0 -90)
			(layer "F.Fab")
			(hide yes)
			(effects
				(font
					(size 1.27 1.27)
					(thickness 0.15)
				)
			)
		)
		(property "Datasheet" "https://eu.mouser.com/datasheet/2/302/PCAL6408A-3139197.pdf"
			(at 0 0 -90)
			(layer "F.Fab")
			(hide yes)
			(effects
				(font
					(size 1.27 1.27)
					(thickness 0.15)
				)
			)
		)
		(property "Author" "Antmicro"
			(at -20 199 0)
			(layer "B.Fab")
			(hide yes)
			(effects
				(font
					(size 1 1)
					(thickness 0.15)
				)
				(justify mirror)
			)
		)
		(property "License" "Apache-2.0"
			(at -20 199 0)
			(layer "B.Fab")
			(hide yes)
			(effects
				(font
					(size 1 1)
					(thickness 0.15)
				)
				(justify mirror)
			)
		)
		(property "MPN" "PCAL6408ABSHP"
			(at -20 199 0)
			(layer "B.Fab")
			(hide yes)
			(effects
				(font
					(size 1 1)
					(thickness 0.15)
				)
				(justify mirror)
			)
		)
		(property "Manufacturer" "NXP"
			(at -20 199 0)
			(layer "B.Fab")
			(hide yes)
			(effects
				(font
					(size 1 1)
					(thickness 0.15)
				)
				(justify mirror)
			)
		)
		(sheetname "Peripherals")
		(sheetfile "peripherals.kicad_sch")
		(attr smd)
		(fp_line
			(start -1.5 1.5)
			(end -0.95 1.501)
			(stroke
				(width 0.15)
				(type solid)
			)
			(layer "B.SilkS")
		)
		(fp_line
			(start 0.95 1.5)
			(end 1.499 1.5)
			(stroke
				(width 0.15)
				(type solid)
			)
			(layer "B.SilkS")
		)
		(fp_line
			(start 1.499 1.5)
			(end 1.5 0.95)
			(stroke
				(width 0.15)
				(type solid)
			)
			(layer "B.SilkS")
		)
		(fp_line
			(start -1.5 0.951)
			(end -1.5 1.5)
			(stroke
				(width 0.15)
				(type solid)
			)
			(layer "B.SilkS")
		)
		(fp_line
			(start -1.5 -0.95)
			(end -1.5 -1.499)
			(stroke
				(width 0.15)
				(type solid)
			)
			(layer "B.SilkS")
		)
		(fp_line
			(start -0.951 -1.499)
			(end -1.5 -1.499)
			(stroke
				(width 0.15)
				(type solid)
			)
			(layer "B.SilkS")
		)
		(fp_line
			(start 1.499 -1.499)
			(end 1.499 -0.95)
			(stroke
				(width 0.15)
				(type solid)
			)
			(layer "B.SilkS")
		)
		(fp_line
			(start 1.499 -1.499)
			(end 0.95 -1.499)
			(stroke
				(width 0.15)
				(type solid)
			)
			(layer "B.SilkS")
		)
		(fp_circle
			(center -1.75 1.07071)
			(end -1.7 1.07071)
			(stroke
				(width 0.15)
				(type solid)
			)
			(fill solid)
			(layer "B.SilkS")
		)
		(fp_rect
			(start -1.75 1.75)
			(end 1.75 -1.75)
			(stroke
				(width 0.05)
				(type solid)
			)
			(fill none)
			(layer "B.CrtYd")
		)
		(fp_line
			(start -1.2 1.5)
			(end -1.5 1.2)
			(stroke
				(width 0.15)
				(type solid)
			)
			(layer "B.Fab")
		)
		(fp_line
			(start 1.499 1.5)
			(end -1.2 1.5)
			(stroke
				(width 0.15)
				(type solid)
			)
			(layer "B.Fab")
		)
		(fp_line
			(start 1.499 1.5)
			(end 1.499 -1.499)
			(stroke
				(width 0.15)
				(type solid)
			)
			(layer "B.Fab")
		)
		(fp_line
			(start -1.5 -1.499)
			(end -1.5 1.2)
			(stroke
				(width 0.15)
				(type solid)
			)
			(layer "B.Fab")
		)
		(fp_line
			(start -1.5 -1.499)
			(end 1.499 -1.499)
			(stroke
				(width 0.15)
				(type solid)
			)
			(layer "B.Fab")
		)
		(fp_text user "${REFERENCE}"
			(at -1.901 -4.998 90)
			(layer "B.Fab")
			(hide yes)
			(effects
				(font
					(size 0.7 0.7)
					(thickness 0.15)
				)
				(justify left bottom mirror)
			)
		)
		(fp_text user "License: Apache-2.0"
			(at -1.901 -7.4 90)
			(layer "B.Fab")
			(hide yes)
			(effects
				(font
					(size 0.7 0.7)
					(thickness 0.15)
				)
				(justify left bottom mirror)
			)
		)
		(fp_text user "Author: Antmicro"
			(at -1.901 -6.2 90)
			(layer "B.Fab")
			(hide yes)
			(effects
				(font
					(size 0.7 0.7)
					(thickness 0.15)
				)
				(justify left bottom mirror)
			)
		)
		(pad "1" smd roundrect
			(at -1.4 0.75 270)
			(size 0.6 0.25)
			(layers "B.Cu" "B.Paste" "B.Mask")
			(roundrect_rratio 0.2)
			(net 351 "/Peripherals/GPIOEX_RESET")
			(pinfunction "~{RESET}")
			(pintype "input")
		)
		(pad "2" smd roundrect
			(at -1.4 0.25 270)
			(size 0.6 0.25)
			(layers "B.Cu" "B.Paste" "B.Mask")
			(roundrect_rratio 0.2)
			(net 353 "/Peripherals/GPIOEX_P0_0")
			(pinfunction "P0")
			(pintype "bidirectional")
		)
		(pad "3" smd roundrect
			(at -1.4 -0.25 270)
			(size 0.6 0.25)
			(layers "B.Cu" "B.Paste" "B.Mask")
			(roundrect_rratio 0.2)
			(net 354 "/Peripherals/GPIOEX_P0_1")
			(pinfunction "P1")
			(pintype "bidirectional")
		)
		(pad "4" smd roundrect
			(at -1.4 -0.75 270)
			(size 0.6 0.25)
			(layers "B.Cu" "B.Paste" "B.Mask")
			(roundrect_rratio 0.2)
			(net 355 "/Peripherals/GPIOEX_P0_2")
			(pinfunction "P2")
			(pintype "bidirectional")
		)
		(pad "5" smd roundrect
			(at -0.75 -1.4 180)
			(size 0.6 0.25)
			(layers "B.Cu" "B.Paste" "B.Mask")
			(roundrect_rratio 0.2)
			(net 356 "/Peripherals/GPIOEX_P0_3")
			(pinfunction "P3")
			(pintype "bidirectional")
		)
		(pad "6" smd roundrect
			(at -0.25 -1.4 180)
			(size 0.6 0.25)
			(layers "B.Cu" "B.Paste" "B.Mask")
			(roundrect_rratio 0.2)
			(net 1 "GND")
			(pinfunction "V_{ss}")
			(pintype "power_in")
		)
		(pad "7" smd roundrect
			(at 0.25 -1.4 180)
			(size 0.6 0.25)
			(layers "B.Cu" "B.Paste" "B.Mask")
			(roundrect_rratio 0.2)
			(net 605 "/Peripherals/GPIOEX_P0_4")
			(pinfunction "P4")
			(pintype "bidirectional")
		)
		(pad "8" smd roundrect
			(at 0.75 -1.4 180)
			(size 0.6 0.25)
			(layers "B.Cu" "B.Paste" "B.Mask")
			(roundrect_rratio 0.2)
			(net 604 "/Peripherals/GPIOEX_P0_5")
			(pinfunction "P5")
			(pintype "bidirectional")
		)
		(pad "9" smd roundrect
			(at 1.4 -0.75 90)
			(size 0.6 0.25)
			(layers "B.Cu" "B.Paste" "B.Mask")
			(roundrect_rratio 0.2)
			(net 546 "/Peripherals/GPIOEX_P0_6")
			(pinfunction "P6")
			(pintype "bidirectional")
		)
		(pad "10" smd roundrect
			(at 1.4 -0.25 90)
			(size 0.6 0.25)
			(layers "B.Cu" "B.Paste" "B.Mask")
			(roundrect_rratio 0.2)
			(net 545 "/Peripherals/GPIOEX_P0_7")
			(pinfunction "P7")
			(pintype "bidirectional")
		)
		(pad "11" smd roundrect
			(at 1.4 0.25 90)
			(size 0.6 0.25)
			(layers "B.Cu" "B.Paste" "B.Mask")
			(roundrect_rratio 0.2)
			(net 281 "~{GPIO_INT}")
			(pinfunction "~{INT}")
			(pintype "output")
		)
		(pad "12" smd roundrect
			(at 1.4 0.75 90)
			(size 0.6 0.25)
			(layers "B.Cu" "B.Paste" "B.Mask")
			(roundrect_rratio 0.2)
			(net 350 "/Peripherals/GPIOEX_I2C_SCL")
			(pinfunction "SCL")
			(pintype "input")
		)
		(pad "13" smd roundrect
			(at 0.75 1.4)
			(size 0.6 0.25)
			(layers "B.Cu" "B.Paste" "B.Mask")
			(roundrect_rratio 0.2)
			(net 349 "/Peripherals/GPIOEX_I2C_SDA")
			(pinfunction "SDA")
			(pintype "bidirectional")
		)
		(pad "14" smd roundrect
			(at 0.25 1.4)
			(size 0.6 0.25)
			(layers "B.Cu" "B.Paste" "B.Mask")
			(roundrect_rratio 0.2)
			(net 87 "+3V3")
			(pinfunction "VDD_{(P)}")
			(pintype "power_in")
		)
		(pad "15" smd roundrect
			(at -0.25 1.4)
			(size 0.6 0.25)
			(layers "B.Cu" "B.Paste" "B.Mask")
			(roundrect_rratio 0.2)
			(net 87 "+3V3")
			(pinfunction "VDD_{(I2C)}")
			(pintype "power_in")
		)
		(pad "16" smd roundrect
			(at -0.75 1.4)
			(size 0.6 0.25)
			(layers "B.Cu" "B.Paste" "B.Mask")
			(roundrect_rratio 0.2)
			(net 352 "/Peripherals/GPIOEX_ADDR")
			(pinfunction "ADDR")
			(pintype "passive")
		)
		(pad "17" smd roundrect
			(at 0 0 270)
			(size 1.68 1.68)
			(layers "B.Cu" "B.Paste" "B.Mask")
			(roundrect_rratio 0.02976190476)
			(net 716 "unconnected-(U34-EP-Pad17)")
			(pinfunction "EP")
			(pintype "power_in+no_connect")
		)
	)
	(footprint "antmicro-footprints:R_0402_1005Metric"
		(layer "B.Cu")
		(at 46.841428 81.615 180)
		(descr "Resistor SMD 0402")
		(tags "resistor SMD 0402")
		(property "Reference" "R165"
			(at 0.781428 -0.425 180)
			(layer "B.SilkS")
			(effects
				(font
					(size 0.7 0.7)
					(thickness 0.15)
				)
				(justify left bottom mirror)
			)
		)
		(property "Value" "R_4k7_0402"
			(at 0 -1.4 0)
			(layer "B.Fab")
			(effects
				(font
					(size 0.7 0.7)
					(thickness 0.15)
				)
				(justify left bottom mirror)
			)
		)
		(property "Footprint" "antmicro-footprints:R_0402_1005Metric"
			(at 0 0 180)
			(layer "F.Fab")
			(hide yes)
			(effects
				(font
					(size 1.27 1.27)
					(thickness 0.15)
				)
			)
		)
		(property "Datasheet" "https://www.bourns.com/docs/product-datasheets/cr.pdf"
			(at 0 0 180)
			(layer "F.Fab")
			(hide yes)
			(effects
				(font
					(size 1.27 1.27)
					(thickness 0.15)
				)
			)
		)
		(property "Author" "Antmicro"
			(at 95.982856 163.23 0)
			(layer "B.Fab")
			(hide yes)
			(effects
				(font
					(size 1 1)
					(thickness 0.15)
				)
				(justify mirror)
			)
		)
		(property "License" "Apache-2.0"
			(at 95.982856 163.23 0)
			(layer "B.Fab")
			(hide yes)
			(effects
				(font
					(size 1 1)
					(thickness 0.15)
				)
				(justify mirror)
			)
		)
		(property "MPN" "CR0402-FX-4701GLF"
			(at 95.982856 163.23 0)
			(layer "B.Fab")
			(hide yes)
			(effects
				(font
					(size 1 1)
					(thickness 0.15)
				)
				(justify mirror)
			)
		)
		(property "Manufacturer" "Bourns"
			(at 95.982856 163.23 0)
			(layer "B.Fab")
			(hide yes)
			(effects
				(font
					(size 1 1)
					(thickness 0.15)
				)
				(justify mirror)
			)
		)
		(property "Tolerance" "1%"
			(at 95.982856 163.23 0)
			(layer "B.Fab")
			(hide yes)
			(effects
				(font
					(size 1 1)
					(thickness 0.15)
				)
				(justify mirror)
			)
		)
		(property "Val" "4k7"
			(at 95.982856 163.23 0)
			(layer "B.Fab")
			(hide yes)
			(effects
				(font
					(size 1 1)
					(thickness 0.15)
				)
				(justify mirror)
			)
		)
		(sheetname "Supply")
		(sheetfile "supply.kicad_sch")
		(attr smd)
		(fp_rect
			(start -0.925 0.47)
			(end 0.925 -0.47)
			(stroke
				(width 0.05)
				(type default)
			)
			(fill none)
			(layer "B.CrtYd")
		)
		(fp_rect
			(start -0.5 0.25)
			(end 0.5 -0.25)
			(stroke
				(width 0.15)
				(type solid)
			)
			(fill none)
			(layer "B.Fab")
		)
		(fp_text user "${REFERENCE}"
			(at -0.95 -3.168 0)
			(layer "B.Fab")
			(hide yes)
			(effects
				(font
					(size 0.7 0.7)
					(thickness 0.15)
				)
				(justify left bottom mirror)
			)
		)
		(fp_text user "Author: Antmicro"
			(at -0.95 -4.169 0)
			(layer "B.Fab")
			(hide yes)
			(effects
				(font
					(size 0.7 0.7)
					(thickness 0.15)
				)
				(justify left bottom mirror)
			)
		)
		(fp_text user "License: Apache-2.0"
			(at -0.95 -5.169 0)
			(layer "B.Fab")
			(hide yes)
			(effects
				(font
					(size 0.7 0.7)
					(thickness 0.15)
				)
				(justify left bottom mirror)
			)
		)
		(pad "1" smd roundrect
			(at -0.48 0 180)
			(size 0.59 0.64)
			(layers "B.Cu" "B.Paste" "B.Mask")
			(roundrect_rratio 0.25)
			(net 1 "GND")
			(pintype "passive")
		)
		(pad "2" smd roundrect
			(at 0.48 0 180)
			(size 0.59 0.64)
			(layers "B.Cu" "B.Paste" "B.Mask")
			(roundrect_rratio 0.25)
			(net 135 "Net-(Q18-G)")
			(pintype "passive")
		)
	)
)
